(kicad_pcb
	(version 20240108)
	(generator "pcbnew")
	(generator_version "8.0")
	(general
		(thickness 1.62)
		(legacy_teardrops no)
	)
	(paper "A4")
	(title_block
		(title "Jetson Orin Baseboard")
		(date "2025-03-12")
		(rev "1.3.4")
		(company "Antmicro Ltd")
		(comment 1 "www.antmicro.com")
		(comment 9 "footprints 58-58 of 677")
	)
	(layers
		(0 "F.Cu" signal)
		(1 "In1.Cu" signal)
		(2 "In2.Cu" signal)
		(3 "In3.Cu" signal)
		(4 "In4.Cu" jumper)
		(5 "In5.Cu" signal)
		(6 "In6.Cu" signal)
		(31 "B.Cu" signal)
		(32 "B.Adhes" user "B.Adhesive")
		(33 "F.Adhes" user "F.Adhesive")
		(34 "B.Paste" user)
		(35 "F.Paste" user)
		(36 "B.SilkS" user "B.Silkscreen")
		(37 "F.SilkS" user "F.Silkscreen")
		(38 "B.Mask" user)
		(39 "F.Mask" user)
		(40 "Dwgs.User" user "User.Drawings")
		(41 "Cmts.User" user "User.Comments")
		(42 "Eco1.User" user "User.Eco1")
		(43 "Eco2.User" user "User.Eco2")
		(44 "Edge.Cuts" user)
		(45 "Margin" user)
		(46 "B.CrtYd" user "B.Courtyard")
		(47 "F.CrtYd" user "F.Courtyard")
		(48 "B.Fab" user)
		(49 "F.Fab" user)
	)
	(footprint "antmicro-footprints:Fiducial_1mm_Mask2mm"
		(layer "F.Cu")
		(at 148.25 127.25)
		(descr "Circular Fiducial, 1mm bare copper, 3mm soldermask opening")
		(tags "fiducial")
		(property "Reference" "FID4"
			(at 0 -1.4 0)
			(layer "F.SilkS")
			(hide yes)
			(effects
				(font
					(size 0.7 0.7)
					(thickness 0.15)
				)
				(justify left bottom)
			)
		)
		(property "Value" "Fiducial_1mm_Mask2mm"
			(at 0 2.2 0)
			(layer "F.Fab")
			(effects
				(font
					(size 0.7 0.7)
					(thickness 0.15)
				)
				(justify left bottom)
			)
		)
		(property "Footprint" "antmicro-footprints:Fiducial_1mm_Mask2mm"
			(at 0 0 0)
			(layer "F.Fab")
			(hide yes)
			(effects
				(font
					(size 1.27 1.27)
					(thickness 0.15)
				)
			)
		)
		(attr board_only exclude_from_pos_files exclude_from_bom)
		(fp_circle
			(center 0 0)
			(end 1.24 0)
			(stroke
				(width 0.05)
				(type solid)
			)
			(fill none)
			(layer "F.CrtYd")
		)
		(fp_circle
			(center 0 0)
			(end 0.999 0)
			(stroke
				(width 0.15)
				(type solid)
			)
			(fill none)
			(layer "F.Fab")
		)
		(fp_text user "${REFERENCE}"
			(at -1.25 4.603 0)
			(layer "F.Fab")
			(hide yes)
			(effects
				(font
					(size 0.7 0.7)
					(thickness 0.15)
				)
				(justify left bottom)
			)
		)
		(fp_text user "Author: Antmicro"
			(at -1.25 5.803 0)
			(layer "F.Fab")
			(hide yes)
			(effects
				(font
					(size 0.7 0.7)
					(thickness 0.15)
				)
				(justify left bottom)
			)
		)
		(fp_text user "License: Apache-2.0"
			(at -1.25 7.003 0)
			(layer "F.Fab")
			(hide yes)
			(effects
				(font
					(size 0.7 0.7)
					(thickness 0.15)
				)
				(justify left bottom)
			)
		)
		(pad "" smd circle
			(at 0 0)
			(size 1 1)
			(layers "F.Cu" "F.Mask")
			(solder_mask_margin 0.5)
			(clearance 0.5)
		)
	)
)
